FILE_TYPE = CONNECTIVITY;
{Allegro Design Entry HDL 16.6-p007 (v16-6-112F) 10/10/2012}
"PAGE_NUMBER" = 236;
0"NC";
1"GND\g";
2"GND\g";
3"GND\g";
4"P5V_STBY\g";
5"GND\g";
6"GND\g";
7"GND\g";
8"GND\g";
9"GND\g";
10"GND\g";
11"GND\g";
12"GND\g";
13"P5V_STBY\g";
14"GND\g";
15"GND\g";
16"P1V05_PCH_STBY\g";
17"P1V05_PCH_STBY\g";
18"GND\g";
19"GND\g";
20"GND\g";
21"PVNN_PCH_STBY\g";
22"GND\g";
23"GND\g";
24"PVNN_PCH_STBY\g";
25"VR_FET_SW_P12V_STBY_PVDDQ_DEF\g";
26"VR_FET_SW_P12V_STBY_PVDDQ_DEF\g";
27"VR_FET_SW_P12V_STBY_PVDDQ_DEF\g";
28"VR_P1V05_PCH_BIREF1";
29"VR_P1V05_PCH_STBY_PH1_PHASE";
30"VR_P1V05_PCH_STBY_PWM1";
31"VR_P1V05_PCH_STBY_PH1_VCIN";
32"VR_P1V05_PCH_STBY_OCSET";
33"VR_P1V05_PCH_STBY_PH1_PHASE_SW";
34"TP_P1V05_PCH_GL_0";
35"VR_PVNN_PCH_PH1_PHASE_SW";
36"A_TSENSE_PVNN_PCH_TMON";
37"VR_PVNN_PCH_PH1_PHASE";
38"VR_PVNN_PCH_PH1_BOOT_R";
39"VR_PVNN_PCH_PH1_BOOT";
40"VR_PVNN_PCH_PWM1";
41"TP_P1V05_PCH_GL_1";
42"VR_P1V05_PCH_STBY_PH1_BOOT_R";
43"VR_P1V05_PCH_STBY_PH1_BOOT";
44"VSENSE_P1V05_PCH_STBY_AVSP";
45"VSENSE_PVNN_PCH_STBY_QAT";
46"VR_PVNN_PCH_AIREF1";
47"VR_PVNN_PCH_PH1_VCIN";
48"VR_PVNN_PCH_STBY_OCSET";
49"UN$236$3D01R5F-GP$I132$2";
50"VSENSE_P1V05_PCH_STBY_AVSN";
51"UN$236$3D01R5F-GP$I137$2";
52"VSENSE_PVNN_PCH_STBY_AVSP";
53"A_TSENSE_P1V05_PCH_STBY_TMON";
54"NC_P1V05_PCH_STBY_PH1_P31";
55"ISENSE_P1V05_PCH_STBY_PH1_IMON";
56"VSENSE_PVNN_PCH_STBY_FPK";
57"VSENSE_PVNN_PCH_STBY_AVSN";
58"TP_PVNN_PCH_GL_1";
59"TP_PVNN_PCH_GL_0";
60"ISENSE_PVNN_PCH_PH1_IMON";
61"NC_PVNN_PCH_PH1_P31";
%"INDUCTOR"
"1","(11150,3950)","0","mstr_discrete","I10";
;
CDS_SEC"1"
CDS_LOCATION"L7A2"
CDS_LIB"mstr_discrete"
ROOM"PVNN_PCH_STBY"
SEC_TYPE"SM"
SEC"1"
MATERIAL"IND"
PACK_TYPE"SM"
VALUE"0.3UH"
PART_NUMBER"D92183-036"
LOCATION"L7A2";
"INA\NAC"
$PN"1"35;
"INB\NAC"
$PN"2"21;
%"GND"
"1","(10375,3575)","0","mstr_symbols","I11";
;
HDL_POWER"GND"
BODY_TYPE"PLUMBING"
ROOM"PVCCIO_CPU0"
BOM_COST"PROC_VRD_PVCCIO_CPU0"
VOLTAGE"0.0V"
CDS_LIB"mstr_symbols"
SIZE"1B";
"A\NAC"1;
%"IR354XX"
"1","(9700,4250)","0","mstr_discrete","I116";
;
CDS_SEC"1"
CDS_LIB"mstr_discrete"
CDS_LOCATION"EU7A3"
PACK_TYPE"SM"
SEC_TYPE"SM"
SEC"1"
PART_NUMBER"H73684-001"
LOCATION"EU7A3"
MATERIAL"IC"
NO_XNET_CONNECTION"1"
VALUE"IR35412";
"TOUT_FLT"
$PN"36"36;
"NC"
$PN"31"61;
"OCSET"
$PN"37"48;
"IOUT"
$PN"38"60;
"SW"
$PN"10"35;
"BOOST"
$PN"33"38;
"REFIN"
$PN"39"46;
"PWM"
$PN"34"40;
"PHASE"
$PN"32"37;
"VIN<0>"
$PN"25"25;
"VCC"
$PN"3"47;
"VIN<1>"
$PN"30"25;
"EN"
$PN"35"4;
"VDRV"
$PN"4"4;
"VOS"
$PN"1"21;
"LGND"
$PN"2"1;
"PGND<1>"
$PN"7"1;
"PGND<2>"
$PN"40"1;
"PGND<0>"
$PN"5"1;
"GL<0>"
$PN"6"59;
"GL<1>"
$PN"41"58;
%"IR354XX"
"1","(9725,2500)","0","mstr_discrete","I117";
;
CDS_SEC"1"
CDS_LOCATION"EU7A2"
SEC"1"
SEC_TYPE"SM"
PACK_TYPE"SM"
CDS_LIB"mstr_discrete"
VALUE"IR35412"
NO_XNET_CONNECTION"1"
MATERIAL"IC"
LOCATION"EU7A2"
PART_NUMBER"H73684-001";
"TOUT_FLT"
$PN"36"53;
"NC"
$PN"31"54;
"OCSET"
$PN"37"32;
"IOUT"
$PN"38"55;
"SW"
$PN"10"33;
"BOOST"
$PN"33"42;
"REFIN"
$PN"39"28;
"PWM"
$PN"34"30;
"PHASE"
$PN"32"29;
"VIN<0>"
$PN"25"26;
"VCC"
$PN"3"31;
"VIN<1>"
$PN"30"26;
"EN"
$PN"35"13;
"VDRV"
$PN"4"13;
"VOS"
$PN"1"16;
"LGND"
$PN"2"14;
"PGND<1>"
$PN"7"14;
"PGND<2>"
$PN"40"14;
"PGND<0>"
$PN"5"14;
"GL<0>"
$PN"6"34;
"GL<1>"
$PN"41"41;
%"RES"
"2","(11975,4425)","0","mstr_discrete","I118";
;
CDS_LOCATION"R3L15"
CDS_LIB"mstr_discrete"
CDS_SEC"1"
$SEC"1"
MATERIAL"EMPTY"
LOCATION"R3L15"
VALUE"68.1K"
TOLERANCE"1%"
PACK_TYPE"0402"
WATTAGE"1/16W"
PART_NUMBER"G21796-187";
"A"
$PN"1"48;
"B"
$PN"2"2;
%"GND"
"1","(11975,4175)","0","mstr_symbols","I119";
;
HDL_POWER"GND"
BODY_TYPE"PLUMBING"
BOM_COST"PROC_VRD_VCCIN_CPU0"
ROOM"PVSA_CPU1_PWR_VR"
VOLTAGE"0"
CDS_LIB"mstr_symbols"
SIZE"1B";
"A\NAC"2;
%"RES"
"2","(12000,2675)","0","mstr_discrete","I120";
;
CDS_LOCATION"R3L14"
CDS_LIB"mstr_discrete"
CDS_SEC"1"
$SEC"1"
PACK_TYPE"0402"
PART_NUMBER"G21796-187"
MATERIAL"EMPTY"
LOCATION"R3L14"
VALUE"68.1K"
TOLERANCE"1%"
WATTAGE"1/16W";
"A"
$PN"1"32;
"B"
$PN"2"3;
%"GND"
"1","(12000,2425)","0","mstr_symbols","I121";
;
HDL_POWER"GND"
BODY_TYPE"PLUMBING"
BOM_COST"PROC_VRD_VCCIN_CPU0"
ROOM"PVSA_CPU1_PWR_VR"
VOLTAGE"0"
CDS_LIB"mstr_symbols"
SIZE"1B";
"A\NAC"3;
%"P5V_STBY"
"1","(8375,5125)","0","mstr_symbols","I122";
;
HDL_POWER"P5V_STBY"
BODY_TYPE"PLUMBING"
VOLTAGE"5.0V"
SIZE"1B"
CDS_LIB"mstr_symbols";
"G\NAC"4;
%"CAP_A"
"1","(8975,2000)","0","dev_discrete","I124";
;
CDS_SEC"1"
$SEC"1"
CDS_LOCATION"CT67"
ROOM"PVCCIN_CPU0_PWR_VR"
CDS_LIB"dev_discrete"
PACK_TYPE"0402V"
MATERIAL"X7R"
TOLERANCE"10%"
VOLTAGE"16V"
VALUE"0.1UF"
LOCATION"CT67"
PART_NUMBER"A36096-030"
STATUS"NOPOP";
"B"
$PN"2"5;
"A"
$PN"1"28;
%"GND"
"1","(8975,1750)","0","mstr_symbols","I125";
;
HDL_POWER"GND"
BODY_TYPE"PLUMBING"
ROOM"PVCCIN_CPU0_PWR_VR"
BOM_COST"PROC_VRD_VCCIN_CPU0"
SIZE"1B"
VOLTAGE"0"
CDS_LIB"mstr_symbols";
"A\NAC"5;
%"GND"
"1","(8975,3475)","0","mstr_symbols","I126";
;
HDL_POWER"GND"
BODY_TYPE"PLUMBING"
VOLTAGE"0"
SIZE"1B"
BOM_COST"PROC_VRD_VCCIN_CPU0"
ROOM"PVCCIN_CPU0_PWR_VR"
CDS_LIB"mstr_symbols";
"A\NAC"6;
%"CAP_A"
"1","(8975,3750)","0","dev_discrete","I127";
;
CDS_SEC"1"
$SEC"1"
CDS_LOCATION"CT66"
ROOM"PVCCIN_CPU0_PWR_VR"
CDS_LIB"dev_discrete"
LOCATION"CT66"
VALUE"0.1UF"
VOLTAGE"16V"
PART_NUMBER"A36096-030"
PACK_TYPE"0402V"
MATERIAL"X7R"
TOLERANCE"10%"
STATUS"NOPOP";
"B"
$PN"2"6;
"A"
$PN"1"46;
%"GND"
"1","(10775,4050)","0","mstr_symbols","I130";
;
HDL_POWER"GND"
BODY_TYPE"PLUMBING"
CDS_LIB"mstr_symbols"
SIZE"1B"
VOLTAGE"0"
ROOM"VDDQ_KLM_PWR_VR";
"A\NAC"7;
%"SC2K2P50V3KX-GP"
"1","(10750,3850)","0","w_hdl","I131";
;
CDS_SEC"1"
$SEC"1"
CDS_LOCATION"CT65"
PART_NUMBER"78.22224.2BL"
PACK_TYPE"SMD-BCG6"
CDS_LMAN_SYM_OUTLINE"-50,25,50,-25"
CDS_LIB"w_hdl"
VALUE"SC2K2P50V3KX-GP"
STATUS"NOPOP"
LOCATION"CT65";
"2"
$PN"2"49;
"1"
$PN"1"35;
%"3D01R5F-GP"
"1","(10750,3575)","4","w_hdl","I132";
;
CDS_SEC"1"
$SEC"1"
CDS_LOCATION"RT43"
PACK_TYPE"SMD-RG5"
PART_NUMBER"64.3R015.16L"
CDS_LIB"w_hdl"
CDS_LMAN_SYM_OUTLINE"-50,75,50,-75"
VALUE"3D01R5F-GP"
STATUS"NOPOP"
LOCATION"RT43";
"2"
$PN"2"49;
"1"
$PN"1"8;
%"GND"
"1","(10750,3375)","0","mstr_symbols","I133";
;
HDL_POWER"GND"
BODY_TYPE"PLUMBING"
ROOM"PVCCIN_CPU0_PWR_VR"
BOM_COST"PROC_VRD_VCCIN_CPU0"
VOLTAGE"0"
SIZE"1B"
CDS_LIB"mstr_symbols";
"A\NAC"8;
%"CAP"
"1","(10750,2575)","0","mstr_discrete","I134";
;
CDS_SEC"1"
$SEC"1"
CDS_LOCATION"CT69"
ROOM"VDDQ_KLM_PWR_VR"
CDS_LIB"mstr_discrete"
VALUE"1000PF"
PACK_TYPE"0402LF"
TOLERANCE"10%"
VOLTAGE"50V"
MATERIAL"X7R"
LOCATION"CT69"
PART_NUMBER"A36096-046"
STATUS"NOPOP";
"A"
$PN"1"53;
"B"
$PN"2"9;
%"GND"
"1","(10750,2400)","0","mstr_symbols","I135";
;
HDL_POWER"GND"
BODY_TYPE"PLUMBING"
ROOM"VDDQ_KLM_PWR_VR"
VOLTAGE"0"
SIZE"1B"
CDS_LIB"mstr_symbols";
"A\NAC"9;
%"CAP"
"1","(10775,4275)","0","mstr_discrete","I136";
;
CDS_SEC"1"
$SEC"1"
CDS_LOCATION"CT64"
CDS_LIB"mstr_discrete"
ROOM"VDDQ_KLM_PWR_VR"
PACK_TYPE"0402LF"
MATERIAL"X7R"
PART_NUMBER"A36096-046"
TOLERANCE"10%"
STATUS"NOPOP"
VALUE"1000PF"
VOLTAGE"50V"
LOCATION"CT64";
"A"
$PN"1"36;
"B"
$PN"2"7;
%"3D01R5F-GP"
"1","(10800,1850)","4","w_hdl","I137";
;
CDS_SEC"1"
$SEC"1"
CDS_LOCATION"RT45"
CDS_LMAN_SYM_OUTLINE"-50,75,50,-75"
CDS_LIB"w_hdl"
PART_NUMBER"64.3R015.16L"
PACK_TYPE"SMD-RG5"
LOCATION"RT45"
VALUE"3D01R5F-GP"
STATUS"NOPOP";
"2"
$PN"2"51;
"1"
$PN"1"10;
%"GND"
"1","(10800,1650)","0","mstr_symbols","I139";
;
HDL_POWER"GND"
BODY_TYPE"PLUMBING"
ROOM"PVCCIN_CPU0_PWR_VR"
BOM_COST"PROC_VRD_VCCIN_CPU0"
VOLTAGE"0"
SIZE"1B"
CDS_LIB"mstr_symbols";
"A\NAC"10;
%"RES"
"1","(7175,5025)","0","mstr_discrete","I14";
;
CDS_SEC"1"
CDS_LOCATION"R3L1"
SEC_TYPE"0402"
SEC"1"
ROOM"PVNN_PCH_STBY"
CDS_LIB"mstr_discrete"
VALUE"1.0"
LOCATION"R3L1"
PART_NUMBER"G21796-090"
TOLERANCE"1%"
WATTAGE"1/16W"
PACK_TYPE"0402"
MATERIAL"CHIP";
"B"
$PN"2"4;
"A"
$PN"1"47;
%"SC2K2P50V3KX-GP"
"1","(10800,2100)","0","w_hdl","I140";
;
CDS_SEC"1"
$SEC"1"
CDS_LOCATION"CT68"
PACK_TYPE"SMD-BCG6"
PART_NUMBER"78.22224.2BL"
CDS_LMAN_SYM_OUTLINE"-50,25,50,-25"
CDS_LIB"w_hdl"
STATUS"NOPOP"
VALUE"SC2K2P50V3KX-GP"
LOCATION"CT68";
"2"
$PN"2"51;
"1"
$PN"1"33;
%"RES"
"1","(7850,4025)","0","mstr_discrete","I141";
;
CDS_SEC"1"
$SEC"1"
CDS_LOCATION"RT44"
ROOM"BMC_DEBUG_HEADER"
BOM_COST"DEBUG"
CDS_LIB"mstr_discrete"
PACK_TYPE"0402"
PART_NUMBER"G21497-005"
WATTAGE"1/16W"
VALUE"0.0"
TOLERANCE"5%"
MATERIAL"CHIP"
LOCATION"RT44";
"B"
$PN"2"38;
"A"
$PN"1"39;
%"RES"
"1","(7900,2300)","0","mstr_discrete","I142";
;
CDS_SEC"1"
$SEC"1"
CDS_LOCATION"RT46"
ROOM"BMC_DEBUG_HEADER"
BOM_COST"DEBUG"
CDS_LIB"mstr_discrete"
PART_NUMBER"G21497-005"
VALUE"0.0"
TOLERANCE"5%"
MATERIAL"CHIP"
WATTAGE"1/16W"
LOCATION"RT46"
PACK_TYPE"0402";
"B"
$PN"2"42;
"A"
$PN"1"43;
%"CAP"
"1","(7750,4550)","0","mstr_discrete","I16";
;
CDS_SEC"1"
CDS_LIB"mstr_discrete"
SEC_TYPE"0402"
SEC"1"
CDS_LOCATION"C7A8"
ROOM"PVNN_PCH_STBY"
MATERIAL"X7R"
VOLTAGE"16V"
TOLERANCE"10%"
VALUE"0.22UF"
LOCATION"C7A8"
PACK_TYPE"0402"
PART_NUMBER"A36096-155";
"A"
$PN"1"4;
"B"
$PN"2"11;
%"CAP_A"
"1","(7625,4550)","2","dev_discrete","I17";
;
CDS_LIB"dev_discrete"
SEC"1"
ROOM"PVNN_PCH_STBY"
CDS_LOCATION"C3L1"
CDS_SEC"1"
SEC_TYPE"0402V"
PART_NUMBER"D97712-004"
PACK_TYPE"0402V"
TOLERANCE"10%"
VOLTAGE"6.3V"
VALUE"1.0UF"
LOCATION"C3L1"
MATERIAL"X6S";
"B"
$PN"2"11;
"A"
$PN"1"4;
%"CAP"
"1","(6925,4500)","0","mstr_discrete","I19";
;
CDS_SEC"1"
CDS_LIB"mstr_discrete"
CDS_LOCATION"C7A6"
SEC_TYPE"0402"
SEC"1"
ROOM"P1V05_PCH_STBY_VR"
TOLERANCE"10%"
VOLTAGE"16V"
MATERIAL"X6S"
LOCATION"C7A6"
VALUE"1.0UF"
PART_NUMBER"D97712-011"
PACK_TYPE"0402";
"A"
$PN"1"47;
"B"
$PN"2"11;
%"CAP_A"
"1","(6550,4525)","0","dev_discrete","I20";
;
CDS_LOCATION"C7A39"
CDS_LIB"dev_discrete"
SEC"1"
SEC_TYPE"0402V"
CDS_SEC"1"
ROOM"PVNN_PCH_STBY"
LOCATION"C7A39"
PART_NUMBER"A36096-030"
VALUE"0.1UF"
TOLERANCE"10%"
PACK_TYPE"0402V"
VOLTAGE"16V"
MATERIAL"X7R";
"B"
$PN"2"11;
"A"
$PN"1"25;
%"CAP"
"1","(6825,3825)","2","mstr_discrete","I21";
;
CDS_SEC"1"
CDS_LOCATION"C7A43"
ROOM"PVNN_PCH_STBY"
SEC"1"
SEC_TYPE"0402"
SPOF"TRUE"
CDS_LIB"mstr_discrete"
LOCATION"C7A43"
MATERIAL"X7R"
VOLTAGE"16V"
PACK_TYPE"0402"
TOLERANCE"10%"
VALUE"0.220UF"
PART_NUMBER"A36096-104";
"A"
$PN"1"39;
"B"
$PN"2"37;
%"CAP"
"1","(6300,4500)","0","mstr_discrete","I22";
;
CDS_SEC"1"
CDS_LIB"mstr_discrete"
CDS_LOCATION"C7A7"
ROOM"PVNN_PCH_STBY"
SEC"1"
SEC_TYPE"0402"
PACK_TYPE"0402"
LOCATION"C7A7"
TOLERANCE"10%"
PART_NUMBER"D97712-011"
VALUE"1.0UF"
VOLTAGE"16V"
MATERIAL"X6S";
"A"
$PN"1"25;
"B"
$PN"2"11;
%"CAP"
"1","(6050,4525)","0","mstr_discrete","I23";
;
CDS_SEC"1"
CDS_LIB"mstr_discrete"
ROOM"PVNN_PCH_STBY"
CDS_LOCATION"C3L12"
SEC"1"
SEC_TYPE"0805"
LOCATION"C3L12"
PART_NUMBER"C95333-007"
VALUE"10UF"
TOLERANCE"10%"
PACK_TYPE"0805"
VOLTAGE"16V"
MATERIAL"X6S";
"A"
$PN"1"25;
"B"
$PN"2"11;
%"CAP"
"1","(5825,4500)","0","mstr_discrete","I24";
;
CDS_SEC"1"
CDS_LIB"mstr_discrete"
CDS_LOCATION"C3L11"
ROOM"PVNN_PCH_STBY"
SEC"1"
SEC_TYPE"0805"
VALUE"10UF"
TOLERANCE"10%"
PACK_TYPE"0805"
VOLTAGE"16V"
MATERIAL"X6S"
LOCATION"C3L11"
PART_NUMBER"C95333-007";
"A"
$PN"1"25;
"B"
$PN"2"11;
%"CAP"
"1","(5575,4525)","0","mstr_discrete","I26";
;
CDS_SEC"1"
CDS_LIB"mstr_discrete"
CDS_LOCATION"C3L8"
SEC_TYPE"0805"
SEC"1"
ROOM"PVNN_PCH_STBY"
LOCATION"C3L8"
PART_NUMBER"C95333-007"
VALUE"10UF"
TOLERANCE"10%"
PACK_TYPE"0805"
VOLTAGE"16V"
MATERIAL"X6S";
"A"
$PN"1"25;
"B"
$PN"2"11;
%"GND"
"1","(5575,4075)","0","mstr_symbols","I27";
;
HDL_POWER"GND"
BODY_TYPE"PLUMBING"
VOLTAGE"0.0V"
SIZE"1B"
CDS_LIB"mstr_symbols"
ROOM"PVCCIO_CPU0"
BOM_COST"PROC_VRD_PVCCIO_CPU0";
"A\NAC"11;
%"GND"
"1","(5600,2350)","0","mstr_symbols","I28";
;
HDL_POWER"GND"
BODY_TYPE"PLUMBING"
ROOM"PVCCIO_CPU0"
BOM_COST"PROC_VRD_PVCCIO_CPU0"
VOLTAGE"0.0V"
CDS_LIB"mstr_symbols"
SIZE"1B";
"A\NAC"12;
%"CAP"
"1","(5600,2825)","0","mstr_discrete","I29";
;
CDS_SEC"1"
CDS_LIB"mstr_discrete"
ROOM"P1V05_PCH_STBY_VR"
CDS_LOCATION"C3L9"
SEC"1"
SEC_TYPE"0805"
MATERIAL"X6S"
PACK_TYPE"0805"
TOLERANCE"10%"
VOLTAGE"16V"
LOCATION"C3L9"
VALUE"10UF"
PART_NUMBER"C95333-007";
"A"
$PN"1"26;
"B"
$PN"2"12;
%"CAP"
"1","(5850,2850)","0","mstr_discrete","I31";
;
CDS_SEC"1"
CDS_LIB"mstr_discrete"
CDS_LOCATION"C3L7"
SEC_TYPE"0805"
SEC"1"
ROOM"P1V05_PCH_STBY_VR"
MATERIAL"X6S"
PACK_TYPE"0805"
TOLERANCE"10%"
VOLTAGE"16V"
LOCATION"C3L7"
VALUE"10UF"
PART_NUMBER"C95333-007";
"A"
$PN"1"26;
"B"
$PN"2"12;
%"CAP"
"1","(6100,2825)","0","mstr_discrete","I32";
;
CDS_SEC"1"
CDS_LIB"mstr_discrete"
ROOM"P1V05_PCH_STBY_VR"
CDS_LOCATION"C3L10"
SEC"1"
SEC_TYPE"0805"
MATERIAL"X6S"
PACK_TYPE"0805"
TOLERANCE"10%"
VALUE"10UF"
VOLTAGE"16V"
LOCATION"C3L10"
PART_NUMBER"C95333-007";
"A"
$PN"1"26;
"B"
$PN"2"12;
%"CAP"
"1","(6350,2825)","0","mstr_discrete","I33";
;
CDS_SEC"1"
CDS_LIB"mstr_discrete"
SEC"1"
CDS_LOCATION"C7A9"
ROOM"P1V05_PCH_STBY_VR"
SEC_TYPE"0402"
LOCATION"C7A9"
VALUE"1.0UF"
TOLERANCE"10%"
PACK_TYPE"0402"
VOLTAGE"16V"
MATERIAL"X6S"
PART_NUMBER"D97712-011";
"A"
$PN"1"26;
"B"
$PN"2"12;
%"CAP"
"1","(6900,2075)","2","mstr_discrete","I34";
;
CDS_SEC"1"
CDS_LOCATION"C7A44"
ROOM"P1V05_PCH_STBY_VR"
SEC"1"
CDS_LIB"mstr_discrete"
SPOF"TRUE"
SEC_TYPE"0402"
VOLTAGE"16V"
PACK_TYPE"0402"
LOCATION"C7A44"
VALUE"0.220UF"
TOLERANCE"10%"
MATERIAL"X7R"
PART_NUMBER"A36096-104";
"A"
$PN"1"43;
"B"
$PN"2"29;
%"CAP_A"
"1","(6575,2850)","0","dev_discrete","I35";
;
CDS_LOCATION"C7A40"
CDS_LIB"dev_discrete"
CDS_SEC"1"
ROOM"P1V05_PCH_STBY_VR"
SEC_TYPE"0402V"
SEC"1"
LOCATION"C7A40"
VALUE"0.1UF"
TOLERANCE"10%"
VOLTAGE"16V"
MATERIAL"X7R"
PACK_TYPE"0402V"
PART_NUMBER"A36096-030";
"B"
$PN"2"12;
"A"
$PN"1"26;
%"CAP"
"1","(6850,2850)","0","mstr_discrete","I36";
;
CDS_SEC"1"
CDS_LIB"mstr_discrete"
CDS_LOCATION"C7A10"
SEC_TYPE"0402"
SEC"1"
ROOM"P1V05_PCH_STBY_VR"
VOLTAGE"16V"
LOCATION"C7A10"
VALUE"1.0UF"
TOLERANCE"10%"
MATERIAL"X6S"
PART_NUMBER"D97712-011"
PACK_TYPE"0402";
"A"
$PN"1"31;
"B"
$PN"2"12;
%"CAP_A"
"1","(7550,2850)","2","dev_discrete","I38";
;
CDS_LOCATION"C3L29"
CDS_LIB"dev_discrete"
CDS_SEC"1"
SEC_TYPE"0402V"
SEC"1"
ROOM"P1V05_PCH_STBY_VR"
PART_NUMBER"D97712-004"
PACK_TYPE"0402V"
MATERIAL"X6S"
VOLTAGE"6.3V"
LOCATION"C3L29"
TOLERANCE"10%"
VALUE"1.0UF";
"B"
$PN"2"12;
"A"
$PN"1"13;
%"CAP"
"1","(7700,2850)","0","mstr_discrete","I39";
;
CDS_SEC"1"
CDS_LOCATION"C7A41"
CDS_LIB"mstr_discrete"
SEC_TYPE"0402"
SEC"1"
ROOM"P1V05_PCH_STBY_VR"
PACK_TYPE"0402"
MATERIAL"X7R"
TOLERANCE"10%"
VALUE"0.22UF"
VOLTAGE"16V"
LOCATION"C7A41"
PART_NUMBER"A36096-155";
"A"
$PN"1"13;
"B"
$PN"2"12;
%"RES"
"1","(7075,3275)","0","mstr_discrete","I41";
;
CDS_SEC"1"
CDS_LIB"mstr_discrete"
CDS_LOCATION"R3L4"
SEC_TYPE"0402"
SEC"1"
ROOM"P1V05_PCH_STBY_VR"
MATERIAL"CHIP"
PART_NUMBER"G21796-090"
LOCATION"R3L4"
PACK_TYPE"0402"
VALUE"1.0"
TOLERANCE"1%"
WATTAGE"1/16W";
"B"
$PN"2"13;
"A"
$PN"1"31;
%"P5V_STBY"
"1","(8375,3400)","0","mstr_symbols","I42";
;
HDL_POWER"P5V_STBY"
BODY_TYPE"PLUMBING"
CDS_LIB"mstr_symbols"
VOLTAGE"5.0V"
SIZE"1B";
"G\NAC"13;
%"GND"
"1","(10375,1850)","0","mstr_symbols","I44";
;
HDL_POWER"GND"
BODY_TYPE"PLUMBING"
BOM_COST"PROC_VRD_PVCCIO_CPU0"
ROOM"PVCCIO_CPU0"
VOLTAGE"0.0V"
SIZE"1B"
CDS_LIB"mstr_symbols";
"A\NAC"14;
%"INDUCTOR"
"1","(11200,2250)","0","mstr_discrete","I45";
;
CDS_SEC"1"
CDS_LIB"mstr_discrete"
CDS_LOCATION"L7A4"
ROOM"P1V05_PCH_STBY_VR"
SEC_TYPE"SM"
SEC"1"
VALUE"0.3UH"
MATERIAL"IND"
PACK_TYPE"SM"
LOCATION"L7A4"
PART_NUMBER"D92183-036";
"INA\NAC"
$PN"1"33;
"INB\NAC"
$PN"2"16;
%"CAP"
"1","(11500,2025)","0","mstr_discrete","I46";
;
CDS_SEC"1"
VOLTAGE"4V"
CDS_LIB"mstr_discrete"
ROOM"P1V05_PCH_STBY_VR"
BOM_COST"PROC_VRD_PVCCIO_CPU0"
SEC_TYPE"0805LF"
SEC"1"
CDS_LOCATION"C7A42"
PACK_TYPE"0805LF"
PART_NUMBER"C95333-002"
MATERIAL"X6S"
TOLERANCE"20%"
VALUE"22UF"
LOCATION"C7A42";
"A"
$PN"1"16;
"B"
$PN"2"15;
%"GND"
"1","(11500,1800)","0","mstr_symbols","I47";
;
HDL_POWER"GND"
BODY_TYPE"PLUMBING"
ROOM"PVCCIO_CPU0"
BOM_COST"PROC_VRD_PVCCIO_CPU0"
VOLTAGE"0.0V"
CDS_LIB"mstr_symbols"
SIZE"1B";
"A\NAC"15;
%"P1V05_PCH_STBY"
"1","(12550,2350)","0","mstr_symbols","I48";
;
HDL_POWER"P1V05_PCH_STBY"
BODY_TYPE"PLUMBING"
VOLTAGE"1.05V"
CDS_LIB"mstr_symbols"
BOM_COST"PROC_VRD_PVCCIO_CPU0"
ROOM"PVCCIO_CPU0";
"G\NAC"16;
%"P1V05_PCH_STBY"
"1","(7675,1500)","0","mstr_symbols","I55";
;
HDL_POWER"P1V05_PCH_STBY"
BODY_TYPE"PLUMBING"
VOLTAGE"1.05V"
CDS_LIB"mstr_symbols"
BOM_COST"PROC_VRD_PVCCIO_CPU0"
ROOM"PVCCIO_CPU0";
"G\NAC"17;
%"RES"
"1","(7350,1300)","0","mstr_discrete","I56";
;
CDS_SEC"1"
CDS_LOCATION"R8B14"
SEC_TYPE"0402"
SEC"1"
MATERIAL"CHIP"
CDS_LIB"mstr_discrete"
ROOM"P1V05_PCH_STBY"
BOM_COST"P1V05_PCH_STBY"
VALUE"0.0"
PACK_TYPE"0402"
WATTAGE"1/16W"
TOLERANCE"5%"
LOCATION"R8B14"
PART_NUMBER"G21497-005";
"B"
$PN"2"17;
"A"
$PN"1"44;
%"RES"
"2","(7000,1050)","0","mstr_discrete","I57";
;
CDS_SEC"1"
CDS_LIB"mstr_discrete"
CDS_LOCATION"R8B15"
SEC_TYPE"0402"
SEC"1"
NO_XNET_CONNECTION"1"
ROOM"P1V05_PCH_STBY"
BOM_COST"P1V05_PCH_STBY"
PACK_TYPE"0402"
TOLERANCE"1%"
MATERIAL"EMPTY"
LOCATION"R8B15"
PART_NUMBER"G21796-017"
VALUE"100.0"
WATTAGE"1/16W";
"A"
$PN"1"44;
"B"
$PN"2"50;
%"GND"
"1","(7650,625)","0","mstr_symbols","I58";
;
HDL_POWER"GND"
BODY_TYPE"PLUMBING"
ROOM"VCCP_CPU0_VR"
BOM_COST"MEM_VRD_PVPP_AB"
CDS_LIB"mstr_symbols"
VOLTAGE"0"
SIZE"1B";
"A\NAC"18;
%"RES"
"1","(7325,850)","0","mstr_discrete","I59";
;
CDS_SEC"1"
MATERIAL"CHIP"
ROOM"P1V05_PCH_STBY"
CDS_LOCATION"R8B12"
CDS_LIB"mstr_discrete"
BOM_COST"P1V05_PCH_STBY"
SEC"1"
SEC_TYPE"0402"
VALUE"0.0"
WATTAGE"1/16W"
PACK_TYPE"0402"
TOLERANCE"5%"
LOCATION"R8B12"
PART_NUMBER"G21497-005";
"B"
$PN"2"18;
"A"
$PN"1"50;
%"CAP"
"1","(12350,1225)","2","mstr_discrete","I63";
;
CDS_LIB"mstr_discrete"
BOM_COST"PVNN_PCH_STBY"
CDS_SEC"1"
$SEC"1"
CDS_LOCATION"C7A13"
ROOM"PVNN_PCH_STBY"
LOCATION"C7A13"
PART_NUMBER"644066-127"
VALUE"100UF"
TOLERANCE"20%"
PACK_TYPE"1210"
VOLTAGE"16V"
MATERIAL"X5R";
"A"
$PN"1"27;
"B"
$PN"2"19;
%"GND"
"1","(12350,925)","0","mstr_symbols","I64";
;
HDL_POWER"GND"
BODY_TYPE"PLUMBING"
BOM_COST"MEM_VRD_PVCCIO_CPU1"
ROOM"PVCCIO_CPU1"
CDS_LIB"mstr_symbols"
VOLTAGE"0.0V"
SIZE"1B";
"A\NAC"19;
%"CAP"
"1","(11975,1250)","2","mstr_discrete","I65";
;
CDS_LIB"mstr_discrete"
BOM_COST"PVNN_PCH_STBY"
CDS_SEC"1"
$SEC"1"
CDS_LOCATION"C7A14"
ROOM"PVNN_PCH_STBY"
LOCATION"C7A14"
PART_NUMBER"644066-127"
MATERIAL"X5R"
TOLERANCE"20%"
PACK_TYPE"1210"
VOLTAGE"16V"
VALUE"100UF";
"A"
$PN"1"27;
"B"
$PN"2"20;
%"GND"
"1","(11975,925)","0","mstr_symbols","I66";
;
HDL_POWER"GND"
BODY_TYPE"PLUMBING"
CDS_LIB"mstr_symbols"
SIZE"1B"
VOLTAGE"0.0V"
BOM_COST"MEM_VRD_PVCCIO_CPU1"
ROOM"PVCCIO_CPU1";
"A\NAC"20;
%"PVNN_PCH_STBY"
"1","(12700,4075)","0","mstr_symbols","I7";
;
HDL_POWER"PVNN_PCH_STBY"
BODY_TYPE"PLUMBING"
VOLTAGE"1.0V"
CDS_LIB"mstr_symbols"
BOM_COST"PROC_VRD_PVCCIO_CPU0"
ROOM"PVCCIO_CPU0";
"G\NAC"21;
%"CAPP"
"1","(11875,3750)","0","mstr_discrete","I71";
;
CDS_SEC"1"
CDS_LIB"mstr_discrete"
SEC_TYPE"SM"
SEC"1"
CDS_LOCATION"C3L18"
ROOM"PVNN_PCH_STBY"
VALUE"470UF"
LOCATION"C3L18"
PART_NUMBER"699013-031"
TOLERANCE"20%"
PACK_TYPE"SM"
VOLTAGE"2V"
MATERIAL"ALUM";
"B"
$PN"2"22;
"A"
$PN"1"21;
%"CAPP"
"1","(12175,3750)","0","mstr_discrete","I73";
;
CDS_SEC"1"
CDS_LIB"mstr_discrete"
SEC_TYPE"SM"
SEC"1"
CDS_LOCATION"C3L20"
ROOM"PVNN_PCH_STBY"
PART_NUMBER"699013-031"
PACK_TYPE"SM"
MATERIAL"ALUM"
VOLTAGE"2V"
LOCATION"C3L20"
VALUE"470UF"
TOLERANCE"20%";
"B"
$PN"2"22;
"A"
$PN"1"21;
%"CAPP"
"1","(12450,3750)","0","mstr_discrete","I74";
;
CDS_SEC"1"
CDS_LIB"mstr_discrete"
SEC_TYPE"SM"
SEC"1"
CDS_LOCATION"C3L21"
ROOM"PVNN_PCH_STBY"
PART_NUMBER"699013-031"
LOCATION"C3L21"
VALUE"470UF"
TOLERANCE"20%"
PACK_TYPE"SM"
VOLTAGE"2V"
MATERIAL"ALUM";
"B"
$PN"2"22;
"A"
$PN"1"21;
%"CAPP"
"1","(12700,3750)","0","mstr_discrete","I75";
;
CDS_SEC"1"
CDS_LIB"mstr_discrete"
CDS_LOCATION"C7A27"
SEC_TYPE"SM"
SEC"1"
ROOM"PVNN_PCH_STBY"
PART_NUMBER"699013-031"
LOCATION"C7A27"
VALUE"470UF"
TOLERANCE"20%"
PACK_TYPE"SM"
VOLTAGE"2V"
MATERIAL"ALUM";
"B"
$PN"2"22;
"A"
$PN"1"21;
%"CAPP"
"1","(11775,2025)","0","mstr_discrete","I76";
;
CDS_SEC"1"
CDS_LIB"mstr_discrete"
CDS_LOCATION"C3L19"
ROOM"P1V05_PCH_STBY"
SEC_TYPE"SM"
SEC"1"
PART_NUMBER"699013-031"
MATERIAL"ALUM"
VALUE"470UF"
LOCATION"C3L19"
VOLTAGE"2V"
TOLERANCE"20%"
PACK_TYPE"SM";
"B"
$PN"2"15;
"A"
$PN"1"16;
%"CAPP"
"1","(12025,2025)","0","mstr_discrete","I77";
;
ROOM"P1V05_PCH_STBY"
CDS_LOCATION"C2L46"
$SEC"1"
CDS_SEC"1"
CDS_LIB"mstr_discrete"
VALUE"470UF"
LOCATION"C2L46"
PART_NUMBER"699013-031"
TOLERANCE"20%"
MATERIAL"ALUM"
VOLTAGE"2V"
PACK_TYPE"SM";
"B"
$PN"2"15;
"A"
$PN"1"16;
%"CAPP"
"1","(12275,2025)","0","mstr_discrete","I78";
;
CDS_LIB"mstr_discrete"
CDS_SEC"1"
$SEC"1"
CDS_LOCATION"C8A15"
ROOM"P1V05_PCH_STBY"
LOCATION"C8A15"
VALUE"470UF"
PACK_TYPE"SM"
MATERIAL"ALUM"
VOLTAGE"2V"
PART_NUMBER"699013-031"
TOLERANCE"20%";
"B"
$PN"2"15;
"A"
$PN"1"16;
%"CAPP"
"1","(12550,2025)","0","mstr_discrete","I79";
;
CDS_LIB"mstr_discrete"
CDS_LOCATION"C2L25"
ROOM"P1V05_PCH_STBY"
CDS_SEC"1"
$SEC"1"
PACK_TYPE"SM"
VOLTAGE"2V"
MATERIAL"ALUM"
PART_NUMBER"699013-031"
TOLERANCE"20%"
VALUE"470UF"
LOCATION"C2L25";
"B"
$PN"2"15;
"A"
$PN"1"16;
%"GND"
"1","(11575,3525)","0","mstr_symbols","I8";
;
HDL_POWER"GND"
BODY_TYPE"PLUMBING"
BOM_COST"PROC_VRD_PVCCIO_CPU0"
ROOM"PVCCIO_CPU0"
VOLTAGE"0.0V"
SIZE"1B"
CDS_LIB"mstr_symbols";
"A\NAC"22;
%"GND"
"1","(9475,850)","0","mstr_symbols","I82";
;
HDL_POWER"GND"
BODY_TYPE"PLUMBING"
ROOM"VCCP_CPU0_VR"
BOM_COST"MEM_VRD_PVPP_AB"
VOLTAGE"0"
CDS_LIB"mstr_symbols"
SIZE"1B";
"A\NAC"23;
%"PVNN_PCH_STBY"
"1","(11550,1575)","0","mstr_symbols","I87";
;
HDL_POWER"PVNN_PCH_STBY"
BODY_TYPE"PLUMBING"
ROOM"PVCCIO_CPU0"
CDS_LIB"mstr_symbols"
BOM_COST"PROC_VRD_PVCCIO_CPU0"
VOLTAGE"1.0V";
"G\NAC"24;
%"CAP"
"1","(11575,3750)","0","mstr_discrete","I9";
;
CDS_SEC"1"
CDS_LIB"mstr_discrete"
VOLTAGE"4V"
ROOM"PVNN_PCH_STBY"
CDS_LOCATION"C7A30"
SEC"1"
BOM_COST"PROC_VRD_PVCCIO_CPU0"
SEC_TYPE"0805LF"
VALUE"22UF"
TOLERANCE"20%"
MATERIAL"X6S"
LOCATION"C7A30"
PART_NUMBER"C95333-002"
PACK_TYPE"0805LF";
"A"
$PN"1"21;
"B"
$PN"2"22;
%"RES"
"1","(10475,1400)","0","mstr_discrete","I90";
;
ROOM"P1V05_PCH_STBY"
MATERIAL"CHIP"
BOM_COST"P1V05_PCH_STBY"
CDS_LOCATION"R7A13"
$SEC"1"
CDS_SEC"1"
SPOF"TRUE"
CDS_LIB"mstr_discrete"
LOCATION"R7A13"
PACK_TYPE"0402"
WATTAGE"1/16W"
TOLERANCE"1%"
VALUE"100.0"
PART_NUMBER"G21796-017";
"B"
$PN"2"24;
"A"
$PN"1"52;
%"RES"
"1","(9850,950)","0","mstr_discrete","I92";
;
CDS_LIB"mstr_discrete"
CDS_SEC"1"
BOM_COST"P1V05_PCH_STBY"
CDS_LOCATION"R7A18"
$SEC"1"
SPOF"TRUE"
ROOM"P1V05_PCH_STBY"
WATTAGE"1/16W"
VALUE"0.0"
MATERIAL"CHIP"
TOLERANCE"5%"
PACK_TYPE"0402"
PART_NUMBER"G21497-005"
LOCATION"R7A18";
"B"
$PN"2"57;
"A"
$PN"1"23;
%"RES"
"1","(8725,1175)","0","mstr_discrete","I93";
;
CDS_SEC"1"
ROOM"P1V05_PCH_STBY"
CDS_LOCATION"R7A19"
SEC"1"
SEC_TYPE"0402"
SPOF"TRUE"
MATERIAL"CHIP"
CDS_LIB"mstr_discrete"
BOM_COST"P1V05_PCH_STBY"
VALUE"10.0"
LOCATION"R7A19"
PART_NUMBER"G21796-066"
WATTAGE"1/16W"
TOLERANCE"1%"
PACK_TYPE"0402"
NO_XNET_CONNECTION"1";
"B"
$PN"2"52;
"A"
$PN"1"45;
%"RES"
"1","(8750,900)","0","mstr_discrete","I94";
;
CDS_SEC"1"
MATERIAL"CHIP"
CDS_LIB"mstr_discrete"
CDS_LOCATION"R7A14"
ROOM"P1V05_PCH_STBY"
SEC"1"
SEC_TYPE"0402"
SPOF"TRUE"
BOM_COST"P1V05_PCH_STBY"
PART_NUMBER"G21796-066"
VALUE"10.0"
WATTAGE"1/16W"
TOLERANCE"1%"
PACK_TYPE"0402"
LOCATION"R7A14"
NO_XNET_CONNECTION"1";
"B"
$PN"2"52;
"A"
$PN"1"56;
%"VCC_CORE"
"1","(5575,4875)","0","mstr_symbols","I95";
;
CDS_LIB"mstr_symbols"
HDL_POWER"VR_FET_SW_P12V_STBY_PVDDQ_DEF";
"A"25;
%"VCC_CORE"
"1","(5600,3125)","0","mstr_symbols","I96";
;
CDS_LIB"mstr_symbols"
HDL_POWER"VR_FET_SW_P12V_STBY_PVDDQ_DEF";
"A"26;
%"VCC_CORE"
"1","(12225,1575)","0","mstr_symbols","I97";
;
CDS_LIB"mstr_symbols"
HDL_POWER"VR_FET_SW_P12V_STBY_PVDDQ_DEF";
"A"27;
END.
